(kicad_pcb
	(version 20260206)
	(generator "pcbnew")
	(generator_version "10.0")
	(general
		(thickness 1.6)
		(legacy_teardrops no)
	)
	(paper "A4")
	(title_block
		(title "Wiwynn_Tioga_Pass_MB.brd")
		(comment 1 "Tioga Pass / footprints 1252-1252 of 4770")
	)
	(layers
		(0 "F.Cu" signal "TOP")
		(4 "In1.Cu" signal "L2GND")
		(6 "In2.Cu" signal "L3")
		(8 "In3.Cu" signal "L4GND")
		(10 "In4.Cu" signal "L5")
		(12 "In5.Cu" signal "L6GND")
		(14 "In6.Cu" signal "L7VCC")
		(16 "In7.Cu" signal "L8VCC")
		(18 "In8.Cu" signal "L9GND")
		(20 "In9.Cu" signal "L10")
		(22 "In10.Cu" signal "L11GND")
		(24 "In11.Cu" signal "L12")
		(26 "In12.Cu" signal "L13GND")
		(2 "B.Cu" signal "BOTTOM")
		(9 "F.Adhes" user "F.Adhesive")
		(11 "B.Adhes" user "B.Adhesive")
		(13 "F.Paste" user "Package Geometry/Pastemask Top")
		(15 "B.Paste" user "Package Geometry/Pastemask Bottom")
		(5 "F.SilkS" user "Ref Des/Silkscreen Top")
		(7 "B.SilkS" user "Ref Des/Silkscreen Bottom")
		(1 "F.Mask" user "Board Geometry/Soldermask Top")
		(3 "B.Mask" user "Board Geometry/Soldermask Bottom")
		(17 "Dwgs.User" user "User.Drawings")
		(19 "Cmts.User" user "User.Comments")
		(21 "Eco1.User" user "User.Eco1")
		(23 "Eco2.User" user "User.Eco2")
		(25 "Edge.Cuts" user "Board Geometry/Outline")
		(27 "Margin" user)
		(31 "F.CrtYd" user "Package Geometry/Place Bound Top")
		(29 "B.CrtYd" user "Package Geometry/Place Bound Bottom")
		(35 "F.Fab" user "Ref Des/Assembly Top")
		(33 "B.Fab" user "Ref Des/Assembly Bottom")
	)
	(footprint ""
		(layer "F.Cu")
		(at 279.6032 -79.6036 180)
		(property "Reference" "C6D4"
			(at 0 0 180)
			(layer "F.SilkS")
			(hide yes)
			(effects
				(font
					(size 1.27 1.27)
				)
			)
		)
		(property "Value" ""
			(at 0 0 180)
			(layer "F.Fab")
			(effects
				(font
					(size 1.27 1.27)
				)
			)
		)
		(duplicate_pad_numbers_are_jumpers no)
		(fp_poly
			(pts
				(xy -0.4953 -0.2032) (xy 0.4953 -0.2032) (xy 0.4953 1.6002) (xy -0.4953 1.6002)
			)
			(stroke
				(width 0)
				(type default)
			)
			(fill no)
			(layer "F.CrtYd")
		)
		(fp_line
			(start 0.4953 1.6002)
			(end -0.4953 1.6002)
			(stroke
				(width 0.1)
				(type default)
			)
			(layer "F.Fab")
		)
		(fp_line
			(start 0.4953 -0.2032)
			(end 0.4953 1.6002)
			(stroke
				(width 0.1)
				(type default)
			)
			(layer "F.Fab")
		)
		(fp_line
			(start -0.4953 1.6002)
			(end -0.4953 -0.2032)
			(stroke
				(width 0.1)
				(type default)
			)
			(layer "F.Fab")
		)
		(fp_line
			(start -0.4953 -0.2032)
			(end 0.4953 -0.2032)
			(stroke
				(width 0.1)
				(type default)
			)
			(layer "F.Fab")
		)
		(pad "1" smd rect
			(at 0 0 180)
			(size 0.762 0.889)
			(layers "F.Cu" "F.Mask" "F.Paste")
			(net "PVCCIO_CPU0")
		)
		(pad "2" smd rect
			(at 0 1.397 180)
			(size 0.762 0.889)
			(layers "F.Cu" "F.Mask" "F.Paste")
			(net "GND")
		)
		(zone
			(layer "F.Cu")
			(hatch none 0.5)
			(connect_pads
				(clearance 0)
			)
			(min_thickness 0.25)
			(keepout
				(tracks not_allowed)
				(vias allowed)
				(pads allowed)
				(copperpour not_allowed)
				(footprints allowed)
			)
			(placement
				(enabled no)
				(sheetname "")
			)
			(fill
				(thermal_gap 0.5)
				(thermal_bridge_width 0.5)
				(island_removal_mode 0)
			)
			(polygon
				(pts
					(xy 279.9842 -80.0481) (xy 279.2222 -80.0481) (xy 279.2222 -80.5561) (xy 279.9842 -80.5561)
				)
			)
		)
	)
)
